# S9S_MB_2U (Grand Teton) — schematic netlist excerpt (pin names and nets, part order shuffled) for the footprints in the layout excerpt that follows; sources: Cadence DE-HDL packaged netlist, KiCad conversion of 03242023_DA0F0TMBIJ0_F0T_Motherboard_J_brd_V01_OCP.brd

R2396  Q_RES  1K 1% CHIP  pkg 0402LF  page 274 : A = P3V3_AUX ; B = PWRGD_PVCCFA_EHV_CPU0_R
PC1588  Q_CAPP  330UF 2V 35% SPCAP  pkg SMLF  page 293 : A = PVCCINFAON_CPU1 ; B = GND

(kicad_pcb
	(version 20260206)
	(generator "pcbnew")
	(generator_version "10.0")
	(general
		(thickness 1.6)
		(legacy_teardrops no)
	)
	(paper "A4")
	(title_block
		(title "03242023_DA0F0TMBIJ0_F0T_Motherboard_J_brd_V01_OCP.brd")
		(comment 1 "Grand Teton / footprints 4595-4596 of 6105")
	)
	(layers
		(0 "F.Cu" signal "TOP")
		(4 "In1.Cu" signal "GND")
		(6 "In2.Cu" signal "IN1")
		(8 "In3.Cu" signal "GND1")
		(10 "In4.Cu" signal "IN2")
		(12 "In5.Cu" signal "GND2")
		(14 "In6.Cu" signal "IN3")
		(16 "In7.Cu" signal "GND3")
		(18 "In8.Cu" signal "VCC")
		(20 "In9.Cu" signal "VCC1")
		(22 "In10.Cu" signal "GND4")
		(24 "In11.Cu" signal "IN4")
		(26 "In12.Cu" signal "GND5")
		(28 "In13.Cu" signal "IN5")
		(30 "In14.Cu" signal "GND6")
		(32 "In15.Cu" signal "IN6")
		(34 "In16.Cu" signal "GND7")
		(2 "B.Cu" signal "BOTTOM")
		(9 "F.Adhes" user "F.Adhesive")
		(11 "B.Adhes" user "B.Adhesive")
		(13 "F.Paste" user "Package Geometry/Pastemask Top")
		(15 "B.Paste" user "Package Geometry/Pastemask Bottom")
		(5 "F.SilkS" user "Ref Des/Silkscreen Top")
		(7 "B.SilkS" user "Ref Des/Silkscreen Bottom")
		(1 "F.Mask" user "Board Geometry/Soldermask Top")
		(3 "B.Mask" user "Board Geometry/Soldermask Bottom")
		(17 "Dwgs.User" user "User.Drawings")
		(19 "Cmts.User" user "User.Comments")
		(21 "Eco1.User" user "User.Eco1")
		(23 "Eco2.User" user "User.Eco2")
		(25 "Edge.Cuts" user "Board Geometry/Outline")
		(27 "Margin" user)
		(31 "F.CrtYd" user "Package Geometry/Place Bound Top")
		(29 "B.CrtYd" user "Package Geometry/Place Bound Bottom")
		(35 "F.Fab" user "Ref Des/Assembly Top")
		(33 "B.Fab" user "Ref Des/Assembly Bottom")
	)
	(footprint ""
		(layer "B.Cu")
		(at 430.600104 -137.542778)
		(property "Reference" "R2396"
			(at 0 0 0)
			(layer "B.SilkS")
			(hide yes)
			(effects
				(font
					(size 1.27 1.27)
				)
				(justify mirror)
			)
		)
		(property "Value" ""
			(at 0 0 0)
			(layer "B.Fab")
			(effects
				(font
					(size 1.27 1.27)
				)
				(justify mirror)
			)
		)
		(duplicate_pad_numbers_are_jumpers no)
		(fp_line
			(start -0.7874 -0.4064)
			(end -0.7874 0.4064)
			(stroke
				(width 0.1524)
				(type default)
			)
			(layer "B.SilkS")
		)
		(fp_line
			(start -0.7874 0.4064)
			(end 0.7874 0.4064)
			(stroke
				(width 0.1524)
				(type default)
			)
			(layer "B.SilkS")
		)
		(fp_line
			(start 0.7874 -0.4064)
			(end -0.7874 -0.4064)
			(stroke
				(width 0.1524)
				(type default)
			)
			(layer "B.SilkS")
		)
		(fp_line
			(start 0.7874 0.4064)
			(end 0.7874 -0.4064)
			(stroke
				(width 0.1524)
				(type default)
			)
			(layer "B.SilkS")
		)
		(fp_line
			(start -0.67945 -0.3048)
			(end -0.67945 0.3048)
			(stroke
				(width 0.1)
				(type default)
			)
			(layer "B.Fab")
		)
		(fp_line
			(start -0.67945 0.3048)
			(end -0.120396 0.3048)
			(stroke
				(width 0.1)
				(type default)
			)
			(layer "B.Fab")
		)
		(fp_line
			(start -0.12065 -0.3048)
			(end -0.67945 -0.3048)
			(stroke
				(width 0.1)
				(type default)
			)
			(layer "B.Fab")
		)
		(fp_line
			(start -0.12065 -0.2794)
			(end -0.12065 -0.3048)
			(stroke
				(width 0.1)
				(type default)
			)
			(layer "B.Fab")
		)
		(fp_line
			(start -0.120396 0.2794)
			(end 0.12065 0.2794)
			(stroke
				(width 0.1)
				(type default)
			)
			(layer "B.Fab")
		)
		(fp_line
			(start -0.120396 0.3048)
			(end -0.120396 0.2794)
			(stroke
				(width 0.1)
				(type default)
			)
			(layer "B.Fab")
		)
		(fp_line
			(start 0.12065 -0.305054)
			(end 0.12065 -0.2794)
			(stroke
				(width 0.1)
				(type default)
			)
			(layer "B.Fab")
		)
		(fp_line
			(start 0.12065 -0.2794)
			(end -0.12065 -0.2794)
			(stroke
				(width 0.1)
				(type default)
			)
			(layer "B.Fab")
		)
		(fp_line
			(start 0.12065 0.2794)
			(end 0.12065 0.3048)
			(stroke
				(width 0.1)
				(type default)
			)
			(layer "B.Fab")
		)
		(fp_line
			(start 0.12065 0.3048)
			(end 0.67945 0.3048)
			(stroke
				(width 0.1)
				(type default)
			)
			(layer "B.Fab")
		)
		(fp_line
			(start 0.67945 -0.305054)
			(end 0.12065 -0.305054)
			(stroke
				(width 0.1)
				(type default)
			)
			(layer "B.Fab")
		)
		(fp_line
			(start 0.67945 0.3048)
			(end 0.67945 -0.305054)
			(stroke
				(width 0.1)
				(type default)
			)
			(layer "B.Fab")
		)
		(pad "1" smd circle
			(at 0.40005 0 180)
			(size 0 0)
			(layers "B.Cu" "B.Mask" "B.Paste")
			(net "P3V3_AUX")
		)
		(pad "2" smd circle
			(at -0.40005 0 180)
			(size 0 0)
			(layers "B.Cu" "B.Mask" "B.Paste")
			(net "PWRGD_PVCCFA_EHV_CPU0_R")
		)
	)
	(footprint ""
		(layer "B.Cu")
		(at 61.62421 -147.84197)
		(property "Reference" "PC1588"
			(at 0 0 0)
			(layer "B.SilkS")
			(hide yes)
			(effects
				(font
					(size 1.27 1.27)
				)
				(justify mirror)
			)
		)
		(property "Value" ""
			(at 0 0 0)
			(layer "B.Fab")
			(effects
				(font
					(size 1.27 1.27)
				)
				(justify mirror)
			)
		)
		(duplicate_pad_numbers_are_jumpers no)
		(fp_line
			(start -4.53898 -2.15011)
			(end -4.53898 2.15011)
			(stroke
				(width 0.1524)
				(type default)
			)
			(layer "B.SilkS")
		)
		(fp_line
			(start -4.53898 2.15011)
			(end 4.53898 2.15011)
			(stroke
				(width 0.1524)
				(type default)
			)
			(layer "B.SilkS")
		)
		(fp_line
			(start 4.53898 -2.150618)
			(end 4.539742 2.152142)
			(stroke
				(width 0.1524)
				(type default)
			)
			(layer "B.SilkS")
		)
		(fp_line
			(start 4.53898 -2.15011)
			(end -4.53898 -2.15011)
			(stroke
				(width 0.1524)
				(type default)
			)
			(layer "B.SilkS")
		)
		(fp_line
			(start 4.53898 2.15011)
			(end 4.53898 -2.15011)
			(stroke
				(width 0.1524)
				(type default)
			)
			(layer "B.SilkS")
		)
		(fp_line
			(start 4.69138 -2.150618)
			(end 4.692396 2.161032)
			(stroke
				(width 0.1524)
				(type default)
			)
			(layer "B.SilkS")
		)
		(fp_line
			(start 4.83108 2.150364)
			(end 4.447794 2.149348)
			(stroke
				(width 0.1524)
				(type default)
			)
			(layer "B.SilkS")
		)
		(fp_line
			(start 4.84378 -2.150618)
			(end 4.53898 -2.150618)
			(stroke
				(width 0.1524)
				(type default)
			)
			(layer "B.SilkS")
		)
		(fp_line
			(start 4.84378 -2.150618)
			(end 4.842256 2.163064)
			(stroke
				(width 0.1524)
				(type default)
			)
			(layer "B.SilkS")
		)
		(fp_line
			(start -3.64998 -2.15011)
			(end -3.64998 2.15011)
			(stroke
				(width 0.1)
				(type default)
			)
			(layer "B.Fab")
		)
		(fp_line
			(start -3.64998 2.15011)
			(end 3.64998 2.15011)
			(stroke
				(width 0.1)
				(type default)
			)
			(layer "B.Fab")
		)
		(fp_line
			(start 3.64998 -2.15011)
			(end -3.64998 -2.15011)
			(stroke
				(width 0.1)
				(type default)
			)
			(layer "B.Fab")
		)
		(fp_line
			(start 3.64998 2.15011)
			(end 3.64998 -2.15011)
			(stroke
				(width 0.1)
				(type default)
			)
			(layer "B.Fab")
		)
		(fp_text user "-"
			(at -4.66979 0.700532 0)
			(unlocked yes)
			(layer "B.SilkS")
			(effects
				(font
					(size 1.905 1.4224)
					(thickness 0.1524)
				)
				(justify left mirror)
			)
		)
		(fp_text user "+"
			(at 6.214872 -0.337058 0)
			(unlocked yes)
			(layer "B.SilkS")
			(effects
				(font
					(size 1.905 1.4224)
					(thickness 0.1524)
				)
				(justify left mirror)
			)
		)
		(fp_text user "-"
			(at -4.313174 -0.094488 0)
			(unlocked yes)
			(layer "B.Fab")
			(effects
				(font
					(size 1.905 1.4224)
					(thickness 0.1524)
				)
				(justify left mirror)
			)
		)
		(fp_text user "+"
			(at 6.214872 -0.337058 0)
			(unlocked yes)
			(layer "B.Fab")
			(effects
				(font
					(size 1.905 1.4224)
					(thickness 0.1524)
				)
				(justify left mirror)
			)
		)
		(pad "1" smd rect
			(at 3.199892 0 180)
			(size 2.413 2.8194)
			(layers "B.Cu" "B.Mask" "B.Paste")
			(net "PVCCINFAON_CPU1")
		)
		(pad "2" smd rect
			(at -3.199892 0 180)
			(size 2.413 2.8194)
			(layers "B.Cu" "B.Mask" "B.Paste")
			(net "GND")
		)
	)
)
